M48
INCH,TZ
T01C.008
T02C.01
T03C.012
T04C.016
T05C.04
T06C.044
T07C.04
T08C.044
T09C.063
T10C.065
T11C.086
T12C.119
T13C.126
T14C.14
;LEADER: 12 
;HEADER: 
;CODE  : ASCII 
;FILE  : 13130-1b-1-12.drl for board 13130-1b.brd ... layers TOP and BOTTOM
;T01 Holesize 1. = 8.000000 Tolerance = +0.000000/-0.000000 PLATED MILS Quantity = 1521
;T02 Holesize 2. = 10.000000 Tolerance = +0.000000/-0.000000 PLATED MILS Quantity = 1152
;T03 Holesize 3. = 12.000000 Tolerance = +0.000000/-0.000000 PLATED MILS Quantity = 23
;T04 Holesize 4. = 16.000000 Tolerance = +0.000000/-0.000000 PLATED MILS Quantity = 343
;T05 Holesize 5. = 40.000000 Tolerance = +0.000000/-0.000000 PLATED MILS Quantity = 4
;T06 Holesize 6. = 44.000000 Tolerance = +0.000000/-0.000000 PLATED MILS Quantity = 10
;T07 Holesize 7. = 40.000000 Tolerance = +0.000000/-0.000000 NON_PLATED MILS Quantity = 2
;T08 Holesize 8. = 44.000000 Tolerance = +0.000000/-0.000000 NON_PLATED MILS Quantity = 6
;T09 Holesize 9. = 63.000000 Tolerance = +0.000000/-0.000000 NON_PLATED MILS Quantity = 5
;T10 Holesize 10. = 65.000000 Tolerance = +0.000000/-0.000000 NON_PLATED MILS Quantity = 1
;T11 Holesize 11. = 86.000000 Tolerance = +0.000000/-0.000000 NON_PLATED MILS Quantity = 3
;T12 Holesize 12. = 119.000000 Tolerance = +0.000000/-0.000000 NON_PLATED MILS Quantity = 2
;T13 Holesize 13. = 126.000000 Tolerance = +0.000000/-0.000000 NON_PLATED MILS Quantity = 2
;T14 Holesize 14. = 140.000000 Tolerance = +0.000000/-0.000000 NON_PLATED MILS Quantity = 4
%
G90
T01
X594500Y4007
X594600Y6707
X504000Y12507
X506800Y12907
X508700Y17207
Y14607
X511800Y12507
X514360Y12417
X519426Y12318
X520700Y14807
X522311Y16720
X523453Y12360
X526000Y12507
X528219Y15096
X528525Y12549
X530700Y15407
X532500Y13407
X537964Y12317
X541114Y12307
X542100Y15107
X544860Y12407
X547500Y12507
X550000
X550234Y14997
X552800Y14807
X553720Y12297
X558448Y12407
X561200Y12507
X564400Y14307
X566040Y12317
X566000Y16507
X568555Y12407
X571600Y14207
X573200Y19907
X573470Y12347
X578620Y12357
X579800Y14807
X582655Y12407
X585280Y12267
X587940Y12417
X590000Y14007
X600896Y12407
X605700
X607300Y14507
X610800Y14807
X610952Y12307
X612000Y17407
X614700Y14107
X615852Y19807
X616600Y12307
X616707Y15616
X619607Y19807
X624000Y12406
X627231Y19907
X633500Y12406
X641745Y12367
X644193Y12907
X645300Y15507
X646800Y17607
X648400Y15490
X648800Y12707
X651316Y12360
X657897Y12504
X662192Y14874
X662359Y12379
X664212Y16356
X665901Y12307
X666175Y14807
X669600Y17907
X671290Y12457
X671500Y15007
X674320Y14219
X675990Y12357
X681280Y12457
X682013Y14848
X684500Y15507
X684760Y12256
X687602Y12439
X690102Y12502
X692200Y15357
X694200Y13507
X699503Y12482
X702000Y12607
X705031Y14515
X705604Y16949
X706360Y12397
X709000Y12407
X712182Y14124
X714000Y12407
X719110Y12347
X720100Y14707
X723586Y14080
X725530Y12507
X728010Y12857
X728500Y15507
X731169Y14584
X732110Y12267
X737300Y12307
X739000Y14407
X742200Y12407
X745100Y12256
X745000Y23000
X744900Y20500
X742100Y28107
X740200Y29907
X736748Y20307
X736091Y23607
X732806
X732000Y20307
X730500Y29907
X728500Y27907
X723500Y29907
X719220Y20553
X718375Y22907
X715090
X714100Y20607
X710813Y28796
X699104Y20495
X698277Y22855
X695029Y22853
X694205Y20302
X689595Y27883
X685400Y28307
X681700Y20507
X680580Y22807
X677295
X676600Y20307
X663300Y23454
X663200Y20956
X663202Y25973
X662916Y28457
X659400Y25907
Y23207
Y20474
X655700Y20225
X655592Y22723
X655602Y25223
X647000Y29607
X645200Y27707
X642451Y20707
X642257Y23307
X642246Y25807
X638507Y23183
X638400Y20607
X638290Y25674
X634757Y22707
Y20207
X634555Y25307
X630955Y25207
X631000Y20107
X631007Y22707
X627255Y25107
X627257Y22407
X623555Y25107
X623532Y20007
X623480Y22564
X619730Y24864
X619700Y22307
X615951Y22356
X615907Y24856
X605728Y20518
X604989Y22907
X601704
X601000Y20507
X583700Y28207
X578600Y20307
X577824Y22907
X574539
X572200Y28707
X569800Y29807
X558500Y20507
X557745Y22907
X554460
X553797Y20496
X549500Y29107
X537410Y20584
X536485Y22907
X533200
X532472Y20515
X519623Y20457
X518769Y22907
X515484
X514300Y20507
X506500Y32807
X507839Y30362
X511589Y30295
X513005Y32412
X519400Y33340
X522700Y30007
X522733Y32832
X525753Y30893
X526700Y33207
X529000Y30007
X529120Y32575
X532350Y30807
X532542Y33307
X537200Y33207
X541950Y33340
X542407Y30882
X545928Y31047
X547306Y33134
X549500Y31607
X553079Y30712
X553250Y33207
X560635Y33264
X561456Y30902
X565091Y30815
X565470Y33287
X570852Y33204
X573242Y32462
X579100Y33207
X581450Y30707
X585179Y30867
X585550Y33340
X589300Y33007
X590500Y30507
X594200Y33607
X594400Y36207
X600360Y33287
X607544Y33340
X607800Y30407
X610500Y30507
X610944Y33333
X615044Y33190
X615103Y30690
X618877Y30790
X618900Y33290
X624100Y33190
X633449
X641900Y31507
X643700Y33290
X644100Y30307
X649550Y30807
X650200Y33307
X657900Y30690
Y33190
X661708Y30699
X662503Y33207
X664678Y30307
X671295Y33190
X671900Y30707
X674400Y31307
X675970Y33267
X681280Y33340
X681900Y30907
X685700Y30807
X687900Y33327
X689624Y30383
X693300Y30607
X693700Y33107
X700940Y33340
X701800Y30807
X704430Y33313
X707157Y33333
X708900Y30407
X712450Y33340
X712400Y30807
X718350Y33107
X721074Y30514
X721747Y32954
X725653Y32654
X727000Y30407
X733474Y33340
X738487Y33094
X742100Y33007
X744800
X747441
X414300Y85600
X411300
X411000Y88900
X407500Y84000
X407400Y87400
X403800Y87000
X403726Y83826
X397300Y89168
X390700Y89300
X387200Y86900
X387100Y83500
X383450Y86900
X383350Y83350
X379500Y86900
Y83302
X375800Y87000
Y83500
X371900Y85400
Y89000
X331200Y88600
X329300Y87300
X315950Y98650
X317641Y90956
X317600Y93625
X318900Y98000
X319520Y92419
X323120Y92400
X326162Y91438
X328000Y97100
Y92700
X330100Y98000
X330900Y93400
X334850Y96900
X335500Y91600
X336750Y93500
Y95704
X344500Y94000
X344523Y98477
X357721Y91779
Y95100
X357900Y99200
X360900Y94200
X361200Y97500
Y90200
X364800Y91200
X364874Y98250
X365000Y94700
X368600Y94100
Y90700
Y97500
X371950Y92500
X375800Y90500
X379500Y90600
X383450Y90500
X387200
X390650Y93000
X390750Y96500
X394100Y99000
Y94900
Y91400
X397100Y96600
X397300Y93100
X400400Y95000
Y92200
Y98500
X403700Y90200
X407400Y91000
X411000Y92100
X414622Y98000
X414672Y94500
X414722Y90250
X418300Y94800
Y91300
X418400Y98150
X422050Y94800
X422000Y91300
X422078Y97678
X426800Y97850
X429500Y93800
X444578Y106201
X442378Y106198
X440178Y106200
X434021Y100128
X429105Y106337
X427560Y104770
X417800Y100400
X412650Y100197
X407550Y100196
X400700Y108800
X392382Y102149
X390683Y108042
X386561Y108812
X382596Y108600
X381950Y100950
X379526Y106396
X368721Y108528
X365316Y108130
X362803Y106035
X361141Y104099
X355175Y108212
X348076Y108910
X347230Y100190
X339500Y102000
X333416Y108899
X333434Y106668
X333313Y103693
X332600Y101400
X330100Y100200
X325081Y100631
X322075Y100650
X315613Y100850
X303610Y110800
X306700Y114700
X306994Y117725
X309000Y114700
X309194Y117700
X311200Y114800
X311410Y118110
X311600Y110800
X315400
X319096Y113300
X320992Y112180
X322010Y118573
X325300Y112300
X325350Y114500
X329415Y119923
X330470Y112515
X330910Y115010
X333534Y118040
X333551Y115090
X338768Y119755
Y116755
X341200Y112569
X343570Y112561
X346596Y115163
Y118163
X351000Y111700
X351342Y114158
X358000Y115500
X359942Y110924
X365721Y115528
X366400Y112200
X370000Y116563
X369997Y113706
X370100Y119563
X372700Y119663
X377818Y115008
X377800Y112063
X381550Y117400
X381600Y119900
X381900Y113000
X385200Y113137
X385600Y116500
X385721Y119528
X389700Y112363
X393331Y118043
X393351Y115107
X396251Y117999
X396600Y112463
X397650Y115500
X401159Y119636
X401353Y116562
X401749Y112418
X404529Y118507
X405200Y115343
X409110Y114910
X409196Y118195
X412462Y115713
X416922Y116613
X416904Y119591
X419596Y113463
X420600Y118300
X422042Y115224
X424700Y115000
X425200Y118823
X427500Y112091
X427900Y114300
X428100Y116500
X430302Y112098
X430342Y119724
X431188Y116105
X434960Y114529
X438500Y116400
X438700Y112900
X453000Y118700
X456200Y118900
X459800Y118800
X463200Y126200
X460100Y123100
X459800Y126200
X459700Y129900
X456500Y126100
Y123000
X456200Y129600
X453000Y123300
X452200Y129800
X444242Y124324
X442842Y120824
X439400Y120100
X439275Y124197
X437800Y128100
X437400Y121600
X435442Y124024
X434700Y128200
X431700Y128300
X431504Y126061
X428255Y126236
X428100Y120000
X427000Y128050
X424982Y126500
X424900Y121213
X423500Y128200
X422300Y126300
X420672Y120600
X418500Y128200
X416851Y122600
X415100Y127900
X413100Y121800
X412600Y124100
X412462Y126300
X409110Y120910
X406200Y127400
X405900Y121700
X404900Y124600
X404400Y128900
X401500Y125600
Y122600
X401256Y128755
X398500Y125604
X398512Y122815
X396700Y128000
X396276Y120948
X393653Y121122
X393561Y127130
X393482Y123982
X390100Y127600
X389914Y124536
X385750Y128517
X385479Y125569
X385523Y122532
X381600Y126427
X381500Y123200
X377800Y124163
X377713Y121061
X372821Y125628
X370121Y125528
X370000Y122563
X367321Y122528
X367221Y125428
X367121Y128628
X362111Y127142
X362120Y124153
X359421Y127128
Y124008
X357300Y128600
X354300
X354333Y125665
X349600Y126700
X349149Y124141
X346600Y121100
X343146Y128473
X343000Y126200
Y124000
X339280Y127380
X336900Y127600
X333977Y127678
X333601Y120500
X331290Y125810
X329308Y122386
X329031Y125428
X326313Y122380
X325418Y127349
X323900Y129900
X323007Y127672
X319418Y123225
X315451Y123219
X312000Y122600
X309700Y122796
X307500Y122700
X305900Y121151
X304149Y128349
X307298Y132697
X307854Y130539
X309000Y137600
X309500Y132925
X312917Y133440
X320321Y130528
X322691Y136023
X325746Y133702
X326322Y138434
X327854Y130434
X329421Y138228
X329693Y134428
X330870Y130540
X332478Y138255
X335303Y135178
X335514Y138220
X338329Y135665
X338470Y138177
X341342Y138224
X341309Y135651
X342533Y133822
X346495Y130000
X347641Y133479
X350800Y138300
X351500Y136000
X355400Y137100
X358500Y137000
X359300Y130000
X362111Y130128
X364600Y137063
X364700Y134000
X367992Y133982
X368026Y137118
X371176Y136890
X374200Y136994
X380400Y133928
X380443Y130102
X380475Y137016
X383567Y137096
X386708Y137118
X389380Y130100
X389848Y137118
X390205Y133858
X392998Y133968
Y137118
X396148Y133968
X396321Y136987
X397800Y130000
X399298Y137118
X399452Y133964
X402561Y137000
X405500Y131063
X408956Y130064
X412100Y135600
X413300Y139100
X415000Y131400
X416000Y135983
X417753Y131322
X419500Y136400
X419499Y139064
X420942Y131324
X422400Y139000
X423900Y131500
X425000Y135350
X426982Y131334
X428390Y139059
X430100Y131500
X432542Y136898
X434700Y131800
X456000Y133500
X459700Y133600
X463100Y133700
X443400Y148900
X443443Y144757
X437398Y146257
X435004Y142110
X431100Y145500
X430694Y142275
X428363Y141756
X427600Y143841
X426900Y147100
X424856Y142270
X423496Y144000
X421500Y142400
X420861Y146923
Y149687
X418000Y142500
X417900Y146900
X415700Y143100
X415100Y149800
X414900Y147000
X413400Y142700
X411900Y146800
X410302Y141864
X409096Y143963
X408800Y147000
X408837Y149809
X407399Y142561
X406042Y147025
X405990Y144251
X403080Y146931
X403132Y144374
X402900Y149663
X402400Y140163
X399298Y140268
X399198Y149618
Y146468
X396182Y149674
X396192Y146444
X396148Y140268
X393204Y146436
X393000Y140268
X392998Y149718
X389848Y146568
X389721Y143320
X387000Y143280
X386853Y149640
X383575Y149603
X383548Y146568
X383395Y143306
X380522Y149564
X380398Y143418
Y146568
X377476Y149688
X374200Y149494
Y140144
Y143294
X368026Y149718
Y143418
Y140268
X368000Y146500
X364886Y140268
X364621Y143328
X361700Y143300
Y146549
X361726Y140268
X361500Y149500
X355460Y149510
X355447Y146528
X355342Y143424
X348743Y146072
X348675Y143326
X348743Y149100
X346450Y149120
X346300Y143000
X346000Y146043
X344500Y141700
X342880Y146180
X339491Y143163
X338320Y141300
X336920Y146130
X336190Y141970
X333750Y145950
X330796Y146221
X330163Y142008
X327963
X327696Y146108
X327390Y149106
X325763Y141958
X325200Y149319
X323550Y142104
X323300Y147046
X319401Y149354
X319252Y140949
X311000Y141731
X305050Y151150
X306696Y158610
X306961Y153717
X309000Y158806
X309220Y153698
X311242Y158732
X311417Y153821
X317698Y152311
X323000Y153900
X324200Y157800
X326234Y153969
X329161Y153830
X329800Y150800
X330300Y158546
X332000Y150800
X332185Y153806
X333000Y158300
X335450Y150900
X335499Y153846
X335964Y158512
X338421Y153802
X341400Y156700
X341390Y153991
X344090Y156690
X344300Y153800
X346944Y156775
X350550Y153280
X350700Y155600
X355400Y152900
X355413Y156050
X358477Y159300
X358500Y155700
X361600Y159250
X364700Y152713
X367900Y152550
X367950Y159200
X371176Y158940
X374100Y159150
X374300Y155800
X377500Y156000
X380400Y152700
X383500Y159000
X386777Y159005
X387000Y155850
X393000Y152663
X393208Y155790
X393198Y158940
X396148Y155790
Y158940
X396200Y152763
X399300Y155963
Y152863
X399298Y158940
X402373Y155952
X402505Y159133
X403078Y152922
X404558Y154835
X406000Y150200
X406100Y159500
X407400Y154863
X407500Y152100
Y157600
X408600Y159600
X410100Y157700
X410272Y154794
X410400Y152000
X411600Y159600
X412900Y157800
X413314Y154908
X415100Y158100
X416400Y155000
X422363Y154700
X425500Y154737
X428400
X431620Y154620
X437472Y152501
X439276Y159645
X439600Y153800
X461200Y167400
X457700
X454200
X435453Y167560
X434834Y163817
X434500Y160037
X431130Y166660
X430600Y164513
X430542Y160753
X428238Y167709
X426900Y160040
X426000Y167370
X423945Y165221
X421710Y167230
X420900Y160037
X420804Y162659
X418439Y167118
X417785Y162622
X414800Y162600
X414572Y165913
X411800Y162700
X411356Y165732
X409300Y167163
X408900Y162463
X407100Y167429
X406000Y162663
X399298Y162090
Y165240
X399300Y168400
X396300Y162100
X393077Y168455
X392998Y165240
X393028Y162059
X386800Y165300
X386777Y162155
X383781Y165235
X383700Y162199
X383548Y168390
X380500Y168500
Y162025
X380398Y165240
X377500
X371157Y162320
X371100Y168700
X368100Y162200
Y165300
X368000Y168500
X364600Y165300
X361500Y168500
X358576Y162090
X358342Y165324
X352000Y162000
X351700Y167300
X351600Y164300
Y169600
X348700Y161700
X348432Y164844
X347500Y169500
X345900Y161700
X344165Y169466
X342716Y161593
X341300Y169600
X339784Y161847
X339747Y164478
X336900Y161600
X336800Y164434
X335400Y169600
X334470Y164760
X333742Y161624
X332353Y169522
X331000Y164500
X330900Y161700
X329442Y169463
X327800Y161500
X326399Y169401
X324953Y161722
X324029Y166384
X319704Y162804
X315384Y166733
X311460Y172078
X323165Y171937
X324436Y175705
X327600Y174174
X327708Y177241
X330027Y174119
X330821Y177402
X332300Y173900
X333842Y177224
X334700Y174100
X336915Y177423
X337000Y174102
X339300Y174100
X339875Y177303
X345562Y178700
X347200Y174300
X350000Y177700
X352200Y171800
X355300Y174600
X361200Y178500
X361500Y175000
X364607Y177103
X364600Y174800
Y171600
X367906Y171458
X370900Y171700
X372400Y179100
X376830Y175640
X376800Y178600
X380540Y177370
X380477Y171605
X383693Y171424
X386600Y174900
X390025Y174672
X393085Y174836
Y171686
X395573Y175400
X396000Y179000
X396225Y171686
X399385
X402540Y171760
X402600Y174611
X405100Y178500
X407552Y170424
X408158Y178666
X410408Y170261
X410620Y173300
X411260Y178090
X413265Y170423
X414960Y178130
X416400Y170300
X417900Y178363
X419340Y170500
X419453Y173187
X420922Y178117
X421697Y174049
X422337Y170575
X423842Y178274
X423910Y175700
X425427Y173113
X425400Y170240
X426970Y178310
X428431Y170264
X428500Y173120
X430340Y177620
X432712Y172469
X434482Y177021
X451000Y171100
X453000Y174900
X454500Y171100
X456500Y174900
X458000Y171100
X460000Y174900
X466900Y178200
X470400
X473900
X473100Y185500
X471300Y181800
X469600Y185500
X469500Y189000
X467800Y181800
X466000Y189000
Y185500
X464300Y181800
X462500Y189000
X435453Y185397
X435105Y181207
X430360Y181350
X429100Y189696
X428400Y185900
X425500Y186045
X423642Y181374
X422152Y189600
X421848Y186550
X419097Y189563
X418600Y182800
X416315Y183219
X415992Y189254
Y186205
X414950Y181460
X412000Y187500
X411553Y181222
X411342Y185024
X408242Y184624
X405231Y184976
X405102Y187874
X403600Y182400
Y180200
X402962Y189014
X400352Y180171
X400252Y182966
X400301Y186099
X397728Y189053
X397307Y186607
X397100Y181000
X395600Y184100
X395641Y188045
X392624Y184537
X392599Y181686
X392596Y187541
X389300Y187700
X384708Y188910
X384740Y180080
X384600Y186100
X384650Y183170
X381800Y183300
X381720Y180220
X381140Y187960
X380510Y185500
X376742Y181524
X372600Y181400
X369200Y189100
X369021Y180128
X369009Y186191
X364792Y188743
X364600Y186138
X361400Y187600
X361300Y184500
X361292Y181409
X356900Y186100
X353302Y182993
X353321Y180128
X353342Y186124
X349751Y187241
X349100Y189700
X345631Y187420
X345500Y184500
X342760Y187810
X342188Y183361
X342233Y185639
X338000Y185700
X337863Y180545
X337800Y189200
X335000Y185500
X334715Y180900
X334707Y189383
X332800Y187700
X332500Y180900
X332100Y185600
X330280Y180900
X329313Y188000
X326500Y187900
X326408Y182292
X323789Y188117
X323500Y180063
X323121Y182913
X320029Y184300
X319942Y180524
X312829Y181940
X311900Y188070
X309700Y187997
X307500Y188000
X305290Y187836
X303480Y189100
X301300Y188700
X301320Y191060
X303500Y195400
X305800
X308200Y195600
X310500
X316844Y196010
X319801Y194890
X322256Y198618
X323331Y196696
X323800Y192150
X326550Y191600
X326850Y193900
X326831Y196119
X329028Y199931
X329972Y196400
Y193559
X333996Y192063
X335400Y196300
X335739Y199317
X337800Y192200
X338048Y196250
X342029Y196427
X342342Y190024
X342339Y192225
X345503Y193474
X345500Y190500
X345837Y199887
X349100Y191900
X349600Y194800
X350409Y199755
X353625Y195045
Y192045
X354700Y199900
X356600Y195700
X356700Y193300
X356800Y191000
X359222Y197700
X361257Y193524
Y190700
X364895Y190941
X364947Y193141
X368455Y196455
X369106Y191903
X371100Y199500
X371299Y196008
X373922Y193103
X374000Y190350
X376800Y193500
X376900Y196600
X381280Y191550
X381460Y195610
X382471Y199843
X384390Y196470
X384684Y191950
X389500Y193600
X389484Y190442
X392600Y190600
X392700Y193563
X395600Y190300
X396200Y194700
X397805Y192061
X403022Y192094
X402967Y195005
X405000Y190700
X405800Y196700
X408100Y193600
X408200Y190500
X412100Y190400
X412200Y192600
X412500Y194900
Y197300
X416139Y192007
X416500Y195563
X418800Y196700
X420800Y193100
X421171Y196496
X421253Y199822
X423800Y196500
X423966Y190846
X426173Y190784
X428830Y195379
X429933Y197283
X431270Y193425
X432100Y190400
X433842Y197021
X435642Y194824
X437921Y192956
X438742Y197224
X443000Y192700
X443100Y195900
X445000Y194500
X450400Y197000
X453400Y193300
X453900Y197000
X456900Y193300
X457400Y197000
X460400Y193300
X459500Y200700
X456000
X452500
X436957Y209867
X427900Y202800
X426311Y204399
X425642Y209524
X424832Y200174
X421811Y202603
X416900Y200100
X416353Y207249
X400400Y209400
X398500Y208000
X384810Y208530
X384644Y205994
X365250Y208600
X359750Y208390
X353792Y208466
X346500Y208350
X339800Y207400
X338967Y209455
X336500Y204600
X327216Y203902
X325642Y202325
X324100Y208000
X321600Y208700
X318700Y207800
X315585Y207787
X311600Y207600
X309100Y206800
X317200Y215300
Y213100
X319400Y216200
X319500Y212100
X321600Y211000
X328510Y218320
X330200Y216800
X331616Y214860
X331658Y212660
X332974Y210874
X336000Y219750
X337307Y217961
X337341Y215731
X337670Y213520
X338926Y211674
X343242Y213690
X343198Y215910
X345300Y216700
X345500Y213000
X347593Y210277
X347664Y212476
X351950Y214800
X353385Y212898
X353594Y210707
X355860Y216690
X357966Y217516
X358382Y212427
X358498Y210220
X359827Y216341
X359910Y214100
X369450Y212040
X369580Y218800
Y215400
X372700Y213700
X372950Y217400
X376300Y211000
Y213700
Y216200
X379700Y219200
Y216500
X379750Y213500
X385900Y218400
X392000Y217200
X392100Y213700
X395700Y217000
Y213600
X399700Y216400
X412100Y218400
X415700Y219200
X415800Y215900
X419600Y216200
Y219200
X420975Y211300
X419550Y222700
X415600
X412000Y222000
X412050Y225100
X408200Y226900
Y223800
X408100Y220500
X404400Y222300
Y225300
Y228600
X399800Y220600
X399700Y225000
X395700Y220600
X395600Y224400
X391950Y220800
X389200Y227400
X389100Y224000
X385900Y222600
X385947Y226500
X382750Y229000
X382700Y226000
X382600Y222600
X372800Y221600
X327024Y220024
X325200Y221700
X313600Y237700
X316000
X319100
X321400
X327100Y237100
X328945Y235846
X331142Y233658
X333036Y231910
X389150Y230300
X659437Y246389
X661200Y248500
X749000Y252200
X744437Y252189
X744100Y254800
X741560Y255000
X739750Y252800
X734937Y253100
X732200Y252200
X730400Y255400
X730300Y257900
X725950Y252573
X724374Y254515
X721600Y257500
X721500Y255000
X721395Y252175
X716737Y252189
X712350Y252640
X711400Y255072
X707800Y255000
X707490Y252310
X704178Y252189
X704137Y254796
X701704Y257549
X701649Y255049
X699800Y252230
X693860Y252210
X692250Y255700
X690000Y256800
X688800Y254600
X688720Y252090
X685382Y252200
X685390Y254900
X682800
X681900Y252500
X674636Y252406
X673770Y254752
X670200Y254700
X669930Y252150
X665500Y252189
X665300Y254700
X653600Y252130
X647800Y252300
X645920Y254130
X643020Y254710
X642802Y252186
X638893Y252206
X638900Y254809
X635197Y254602
X635043Y252106
X615532Y259700
X611845Y253723
X611706Y259387
X609937Y252106
X609500Y254900
X608700Y257300
X606700Y255600
X604074Y254394
X603187Y252056
X591342Y252206
X591300Y255010
X590837Y259889
X589500Y257100
X587700Y255300
X587642Y252206
X582300Y254900
X582200Y252206
X579205Y254850
X578800Y252200
X572150
X571867Y254685
X568327Y253348
X566151Y252115
X565054Y254773
X563376Y256627
X561419Y254850
X560555Y252503
X553485Y252332
X552800Y255300
X551000Y252056
X550200Y255500
X545500Y252600
X544800Y255100
X541005Y254800
X540900Y252300
X535098Y252600
X532900Y255300
X531775Y252231
X530015Y255000
X527400Y252100
X526715Y254700
X522908Y255117
X521800Y252875
X516600Y252200
X514137Y256089
X513776Y258563
X511640Y255956
X511200Y258900
X507817Y252248
X517100Y265100
X517846Y262489
X521131
X521987Y265100
X534700
X535562Y262489
X538847
X539505Y265100
X554500Y264900
X555641Y262489
X558926
X559700Y264900
X570200Y269700
X572155Y264900
X573357Y262489
X576642
X577450Y264900
X589900Y268133
X590322Y262361
X590700Y264833
X594500Y265200
X594559Y262559
X594600Y260000
X598300Y265400
X598418Y262699
X598398Y260199
X606200Y267800
X611536Y264385
X611593Y261885
X615430Y262213
X615537Y264789
X619100Y265300
X619180Y262689
X619382Y260089
X622899Y265189
X622933Y260189
X622930Y262689
X626680Y262989
X626651Y265489
X626682Y260300
X630432Y260100
X630457Y262832
X630455Y265400
X634207Y260300
X634280Y265332
Y262832
X638032Y260342
X637987Y262842
X638090Y265340
X639500Y268800
X644550Y267170
X648200Y265300
X648948Y262489
X652233
X653000Y264900
X675400Y265000
X676113Y262489
X679398
X680600Y265000
X683100Y268000
X691900Y269300
X695500Y265000
X696192Y262489
X699477
X700200Y264900
X716795Y265000
X717452Y262489
X720737
X721400Y265000
X729860Y269810
X734200Y265100
X735168Y262489
X738453
X739111Y264962
X753000Y272100
X746737Y272889
X744200Y272600
X741200Y270500
X739838Y272813
X734510Y273110
X732740Y270200
X730400Y272850
X727800Y272800
X725300
X722400Y270800
X721395Y273100
X716737Y272989
X715900Y270000
X713100Y273000
X712200Y270500
X709400Y272600
X706900Y273000
X706000Y270500
X704277Y272989
X701300Y270777
X700300Y273100
X695500
X692537Y272989
X689700Y270800
X687682Y272889
X685100Y273100
X682481Y270700
X680400Y273100
X675400
X672800Y272700
X669700Y270900
X668000Y272890
X665100Y272700
X664500Y270000
X661600Y272300
X659500Y274000
X653041Y272989
X648291Y273140
X646360Y271530
X644090Y270420
X642937Y273089
X637337Y272944
X637288Y270100
X629937Y272990
X620437
X612393Y273026
X609896Y272889
X608996Y270206
X605065Y272967
X605100Y270100
X602450Y272900
X595386Y272932
X591536Y273000
X591500Y270100
X588400Y270300
X588036Y273089
X582600Y270300
X580200Y273000
X580107Y270501
X577636Y272947
X572700Y273100
X570200
X567800Y270500
X565700Y273050
X564100Y271100
X560600Y270300
X559600Y272900
X554434Y272914
X551937Y272789
X548800Y271000
X546900Y273100
X546200Y271000
X544292Y273128
X541500Y270900
X539937Y272989
X534905Y273097
X534100Y270700
X530900Y273000
X529300Y271000
X528330Y273140
X525845Y272863
X522992Y270700
X521790Y273140
X516727Y273122
X514900Y271350
X511736Y273001
X509244Y272796
X506496Y272500
T02
X17500Y190200
X16844Y203100
X17301Y212401
X17300Y218307
X16400Y224212
X10000Y229500
X16118Y230118
X13090Y231129
X9500Y234200
X13090Y234899
X16300Y236023
X7600Y237091
Y240861
X16899Y241929
X13590Y242940
X10194Y243106
X13590Y246710
X10190Y246699
X16899Y247834
X7600Y248902
Y252672
X16899Y253740
X13590Y254751
X10194Y254917
X10190Y258510
X13590Y258521
X16899Y259645
X7600Y260713
Y264483
X16899Y265551
X7600Y268100
X16900Y269000
X37900Y257500
Y254000
X38000Y250500
X37900Y247000
Y243500
Y240000
X38000Y236500
X37900Y233000
Y229500
Y226000
Y222500
Y219000
X34500Y216000
X37600Y212700
X34800Y212200
Y208300
X37600Y207800
X31500Y207500
X21900Y205400
X37600Y203700
X34800
X32000Y203200
Y199300
X34800Y198800
X37600
X30000Y196200
X33500Y196100
X37900Y195300
X26500Y181800
X23100
X33150Y181500
X29400Y180000
X33500Y178100
X38500Y148000
X29700Y141200
X38500Y138500
X30000Y136000
X32800Y120400
X29200Y120300
X25800
X28400Y81400
X41200Y90300
X42000Y96000
X57500Y96500
X52500
X41500Y100800
X55000Y101500
X50000
X57500Y106500
X52500
X55000Y111300
X50000
X53500Y120400
X40500Y124300
Y127700
X56100Y130700
X52643Y130800
X57600Y136900
X43500Y138500
X48500
X58000Y141750
X41000Y143300
X46000
X48500Y148000
X43500
X46000Y152300
X41000
X45800Y158100
X58800Y177000
X59379Y184380
X55720
X52700Y184800
X51860Y187640
Y191410
X54700Y192200
X40400Y207800
X57400Y210700
X40400Y212700
X57600Y214200
X40400Y217100
X57287Y219806
X57500Y223200
X40700Y224000
X57600Y226600
X44861Y227261
X57009Y230009
X40200Y231300
Y238300
X56724Y243300
X40200Y245300
X58102Y246471
X56800Y249613
X44400Y250400
X40600Y252500
X57800Y253900
X40500Y260000
X57800Y264100
Y267500
X50000Y270000
X46800Y274500
X78200Y275600
X66800Y275200
X64700Y272500
X74000Y271400
X71800Y268800
X67000Y263200
X75300Y259900
X78700Y259800
X66300Y259300
X67600Y255800
X79000Y246900
X75600Y246700
X69400Y246000
X72600Y244800
X79500Y230000
X72137Y210237
X74800Y191000
X62800Y184300
X66500Y128000
X65500Y123800
X60000Y111300
Y101500
X69235Y99735
X68200Y94900
Y91500
X60800Y87500
X62900Y79900
X79700Y67500
X78300Y64300
X79115Y60979
X76411Y40357
X74000Y37642
X66500
X98500
X82211Y37747
X89862Y37849
X95779Y40357
X92159
X80031
X96800Y53300
X85300Y54400
X88700
X83600Y57600
X89400Y58200
X96200Y60700
X82885Y60979
X90600Y63200
X94000Y63300
X97900Y76200
X94500
X91500Y84000
X89800Y87300
X90000Y91000
X86100Y97700
X90500Y101000
X86500Y113500
X80500
X85500Y135400
X97100Y189200
X83500Y191000
X86900
X84700Y197100
X95700Y197200
X85898Y200598
X92900Y204008
X89500Y204000
X80563Y214700
X90812Y215000
X95200Y216200
X84500Y225000
X99600Y225700
X84500Y230000
X89500
X84500Y235000
X99328Y235370
X97600Y246500
X82400Y246600
X88900Y246700
X82100Y259600
X83900Y269500
X80500
X91400Y270300
X109500Y258300
X104900Y248800
X110166Y239500
X109000Y231400
X112700
X112800Y225400
X112700Y221200
X100600Y221100
X111900Y209000
X107740Y204460
X102000Y203200
X110000Y201900
X115760Y191419
X119760
X106100Y158700
X119600Y143300
X112550Y142800
X118500Y125500
X111200Y67200
X109600Y63700
X114800Y60700
X109700Y60000
X104400Y57700
X119200Y57400
X115800
X100050Y54400
X103450
X111527Y40357
X107907
X105794Y37692
X113605Y37665
X121500Y37642
X137300
X129336Y37652
X139403Y40357
X123655
X127275
X120000Y40700
X136600Y44800
X120200Y45610
X138000Y49800
X131600Y57400
X135000
X138574Y57924
X121400Y60100
X130400Y60600
X136400
X137138Y76512
X121295Y77502
X125787Y78813
X121170Y80900
X129300Y84900
X134200Y86100
X126000Y86200
X136469Y89902
X130315Y90533
X133558Y91779
X136600Y93300
X136500Y101523
Y104923
X136540Y108620
X136770Y113000
X130000Y121000
X126950Y125200
X130563
X136500Y126300
X133975Y129141
X127500Y129180
X133786Y134700
X130300Y135000
X120700Y135500
X136156Y138025
X120500Y139000
X135412Y141400
X131762Y141796
X138600Y146300
X131500Y149000
X132700Y158600
X127200Y158700
X137300Y158900
X125000Y178000
X137100Y188900
X123760Y191419
X128000Y203300
X144200Y270700
X155300Y254000
X146500Y236500
X146000Y231000
X150000Y210100
X153500Y210000
X142997Y207891
X146396Y207675
X153000Y201900
X146980Y200580
X140000Y195500
X150500Y183000
X157000Y169194
X158500Y161820
X144500Y158900
X140800
X150804Y158896
X157500Y149025
X147808Y145208
X142900Y138595
X146400
X153693Y124807
X150670Y122300
X157229Y119218
X150670Y118900
X157175Y115462
X150670Y115500
X158305Y112180
X150670Y112100
X154550Y106200
Y102800
X150670Y102720
X151080Y99344
X158105Y96775
X152811Y84300
X150894Y76497
X154294Y76506
X153000Y67800
X147400Y60400
X144995Y57995
X154615Y54500
X143700Y54503
X147315Y54400
X150715
X159060Y48610
X155290
X143688Y48350
X158771Y40357
X143023
X155151
X153088Y37653
X145070Y37642
X176640Y37699
X160898Y37704
X168791Y37689
X170899Y40357
X174519
X174060Y49600
X170290
X159957Y51932
X175758Y52879
X169600Y53000
X163063Y54400
X179000
X166463
X164000Y65000
X179800Y65700
X176900Y67500
X167500Y68000
X174900Y77700
X172199Y91591
X179400Y94200
X173000Y97000
X178000Y97300
X172300Y107189
X171800Y126600
X175787Y127000
X177200Y130575
X176700Y144875
X177200Y148700
X162900Y152200
X167602Y160684
X161900Y161700
X167581Y164084
X177159Y172900
X170910Y173840
X167140
X176400Y175700
X163700Y178900
X169800Y181448
X165900Y181500
X175546Y192509
X165700Y203400
X174739Y207381
X177500Y209500
X167000Y221500
X162000
X167000Y226000
X162000
X167000Y230500
X162000
Y235000
X176800Y241600
X165700Y254000
X195000Y234000
X187000Y209500
X198198Y206374
X191400Y206100
X194800
X195630Y192770
X180546Y192509
X185546
X199392Y190947
X199441Y187547
X196000Y186897
X191200Y181068
X180931Y172985
X186300Y172400
X181000Y167500
X199900Y154200
X197140Y152010
X194623Y149723
X192237Y147300
X187597Y133697
X194900Y124200
X188363Y116137
X187500Y106500
X183726Y106353
X181732Y97500
X193005Y97155
X189106Y97235
X195989Y95300
X183344Y94056
X191500Y94100
X188900Y91800
X198500Y83800
X193485Y83724
X197845Y80360
X194075
X180700Y78500
X184300
X196900Y68700
X193500
X190100
X197700Y54400
X194700
X181800
X189700Y54300
X186865
X191700Y52100
X185000Y51600
X186647Y40357
X194445Y40395
X198073
X190267Y40357
X184500Y37700
X192400Y37642
X200300
X216085Y37649
X207600Y37642
X219900Y39100
X201500Y54500
X208700Y54900
X205300
X219899Y56800
X210900Y57600
X214942Y67242
X211600Y82100
X212300Y85500
X202200Y89500
X202500Y97000
X213558Y98500
X207200Y106000
X201650Y111200
X205689Y112879
X209259Y113771
Y117430
X205850Y118175
X209900Y120900
X206605Y121741
X201899Y134200
X205380
X210100Y135800
X201252Y137766
X206790Y139040
X210547Y139028
X200900Y177000
X213850Y179850
X202761Y186811
X207861Y188540
X202800Y191400
X215100Y194200
Y199400
X215384Y202984
X201596Y206504
X205000Y206500
X212500Y219500
X208800
X216000
X205920Y221550
X206000Y234000
X227000Y275500
X232560Y204250
X232225Y193275
X236861Y184967
X233350Y180700
X239900Y180600
X224200Y180200
X236477Y179357
X227870Y170252
X232921Y167505
X226452Y147300
X231562Y143827
X234875Y143060
X228000Y139700
X234875Y139290
X231611Y138336
X233452Y108588
X228000Y108304
X230875Y106300
X235075Y105600
X227894Y104600
X227800Y101200
X227850Y97575
X232600Y95300
X226500Y94450
X236700Y88500
X229036Y83000
X230000Y66400
X221400Y64500
X235400Y63400
X230400Y63000
X223800Y61700
X233981Y59125
X223475Y53300
X238800Y45300
X236211Y43057
X232591
X229300Y42950
X239599Y37673
X223868Y37686
X231780Y37691
X255000Y37642
X247500
X245385Y40357
X241765
X254600Y41100
X244400Y50600
X259000Y57800
X250500Y57900
X253500
X256200Y59200
X240200Y59275
X247500Y60000
X240297Y63400
X240300Y67200
X243200Y73700
X246600
X250300Y73800
X253700Y75875
X244759Y85200
X241200Y94900
X258634Y95850
X244800Y100700
X259820Y103454
X244463Y130655
X242950Y155800
X244715Y159785
X257977Y163423
X257687Y169870
X253500Y174360
X247596Y174667
X240119Y183993
X253300Y189834
X240100Y191000
X246689Y196687
X257500Y266645
X267000Y271300
X260500Y264630
X278700Y254240
X275300Y254100
X267275Y253400
X263600Y252700
X269800Y250700
X265500Y249300
X263600Y239850
X275400Y237900
X270774Y222226
X274700Y222100
X278450Y216800
X265259Y216659
X270341Y211835
X261200Y209700
X266140Y191850
X262700Y191500
X276910Y189400
X273060Y189374
X269772Y188274
X261300Y188300
X278300Y173300
X264600Y173100
X268283Y173035
X274100Y163300
X270500Y163200
X267456Y160156
X272380Y159240
X270500Y156250
X267100Y156200
X273900Y156198
X272300Y149900
X267187Y149800
X268300Y141869
X278000Y141900
X263775Y140327
X272300Y129442
X268900Y129386
X278075Y116475
X268928Y112625
X272185Y111831
X272200Y108352
X268895Y107350
X262131Y100959
X264189Y98252
X275900Y88200
X264125Y79350
X275200Y78700
X264500Y73100
X264700Y59400
X262000Y57800
X268000Y57500
X271000
X278868Y56000
X274000Y55800
X275300Y44900
X261900
X269800Y44800
X278700
X268910Y40490
X265140
X271000Y37800
X263100Y37700
X278800
X286900Y37800
X294500Y37900
X284758Y40490
X280988
X296736
X284000Y55800
X290200Y57900
X286800
X292500Y60500
X295300Y66200
X288700Y71100
X292100
X299800Y82300
Y85950
X280100Y89100
X297150Y91100
X288400Y94200
X299300Y98500
X281005Y99105
X288100Y99500
X281475Y116475
X286500Y119900
X296564Y127500
X280400Y129225
X285100Y129510
X296531Y133061
X286600Y136000
X296564Y136311
X281500Y142100
X295900Y154200
X297000Y160200
X297250Y163700
X287071Y173154
X282950Y181350
X296600Y189100
X282460Y189400
X286300Y191885
X287700Y211900
X293300Y212400
X291201Y225025
X287802Y225200
X287600Y238100
X295300
X298900Y253300
X295500Y253500
X287400Y254100
X285000Y261700
X281599Y261799
X287250Y269250
X316945Y281606
X313824Y280255
X319400Y278800
X311300Y277800
X316400Y276800
X311400Y269200
X309000Y266700
X318600Y264300
X304300Y262900
X319000Y254200
X315500Y254100
X302600Y253600
X306000
X309400
X307300Y224900
X309900
X304400
X305300Y203125
X310579Y182800
X307200Y182000
X304400
X301745Y181788
X309200Y180500
X305091Y173888
X302591Y173906
X309112Y171960
X306612Y171882
X307231Y164059
X301109Y146156
X300700Y142850
X312150Y100682
X303400Y98500
X301300Y97000
X303376Y95200
X301600Y93300
X306100Y90600
X304400Y88400
X309400Y82100
X312400Y79700
X318882Y71643
X302400Y59500
X311598Y57522
X304800Y57400
X315800
X308200
X319200
X311950Y50800
X314800Y48625
X300900Y46900
X312484Y40690
X316254
X300506Y40490
X310348Y37900
X302600Y37800
X318048Y37700
X326096Y37900
X333700Y38000
X328303Y40995
X331931
X321900Y44000
X327577Y48475
X331300
X320400Y48600
X324176
X327400Y54900
X324000
X328300Y58200
X322548Y58300
X333600Y63800
X328882Y71643
X323882
X337000Y74202
X326000Y254100
X322500Y254200
X322000Y264300
X326100Y267000
X322700Y277700
X325100Y281500
X321600Y282500
X342600Y277900
X349900Y263800
X356432Y43657
X356971Y37700
X367520Y37642
X363583
X371457
X375400Y37700
X363604Y41042
X367497
X364600Y44298
X366484Y47129
X362626Y47068
X366700Y68700
X369500Y234600
X373000Y236000
X369500Y237200
X373000Y238900
X369500Y240600
X373000Y242300
X369500Y244000
X376500Y263461
X365800Y264900
X362400
X369300
X379300Y275300
X386100
X389500
X382700
X393000Y275000
X390500Y268800
X391000Y265000
X383500Y263461
X380000
X399438Y243839
X394229Y241128
X397400Y239700
X391788Y238760
X393000Y236200
X388000Y72963
X385300Y47000
X401838Y246248
X405700Y246500
X417000Y258000
X416128Y272896
X400900Y273000
X436600Y275000
X429900Y274940
X426600Y274100
X433300
X423000Y274000
X420500Y257800
X423900Y257500
X423600Y246700
X433129Y245783
X426600Y244450
X430000
X420000Y244000
X435700Y243250
X423000Y43900
X422986Y40350
X424536Y34800
X436106Y34506
X430000Y34158
X424599Y31300
X436100Y30900
X430000Y30758
X424543Y27900
X430000Y27358
X436240Y26300
X426405Y25054
X424543Y22208
X430000Y21500
X427000Y17000
X430500
X423500Y16885
X437061Y10393
X432200Y9103
X425400
X428800
X422000
X434900Y6925
X438300
X449600Y5900
X446200
X442100Y7006
X450200Y9800
X446800Y9900
X441281Y17025
X449734Y18681
X446100Y18700
X451300Y21700
X444783Y28451
X441390Y28680
X451000Y257413
X449400Y273700
X440600Y274300
X445300Y274400
X452500Y275200
X456300Y275300
X469000Y275200
X464000
X460400
X472400Y275100
X466500Y272800
X472101Y266090
X479000Y265900
X475500
X467700Y245500
X467100Y154200
X470100
X477000Y154050
X473500
X498500Y88995
X493000Y119299
X483800Y154050
X480400
X487200Y154100
X495400Y183500
X482400Y266200
X497002Y275400
X505315Y268500
X513100Y234500
X516500
X510675Y209700
X514800Y183400
X504400
X500900
X511200
X518200
X508000Y119500
X511500
X515000Y119270
X518902Y88987
X515502Y88998
X502000Y89000
X539574Y88990
X525740Y88960
X533267Y89634
X522280Y89810
X528985Y89975
X533000Y119500
X524700
X528100
X536400
X528400Y145041
X524700
X526600Y183500
X530214Y183481
X534750Y183600
X538150
X531500Y219500
X531000Y228350
X541500Y234900
X550400Y222285
X558300Y210000
X551700Y209800
X548300Y209700
X558915Y183603
X541550Y183550
X551754Y183600
X544954
X548354
X555500Y183500
X557100Y136000
X552100
X546349Y89512
X542950Y89400
X552900Y89100
X556500Y89000
X555199Y69700
X558599
X548400
X551800Y69600
X561999Y69700
X578400Y89100
X570715
X566000
X575000
X562000Y127800
X572100Y136000
X562100
X567100
X562000Y144900
X572845Y183300
X569395
X578795
X566897Y183405
X576295Y183400
X564398Y183481
X561900Y183600
X573600Y190100
X561000Y222700
X569200Y223600
X564200Y224000
X561196Y227366
X586800Y213200
X591363Y208387
X583800Y207200
X580350Y207250
X588800Y205900
X591850Y187725
X594350
X593475Y183275
X590975
X584800Y183300
X588475
X582254Y183313
X599150Y180300
X599200Y145000
X592200
X588800
X595744Y145041
X593400Y126000
X588600Y124700
X599300Y119270
X596845Y89624
X590898Y89045
X587500Y88913
X599500Y87500
X612120Y121750
X608360Y121800
X617700Y125500
X608300Y144890
X618500Y159000
X601750Y182500
X605600Y186650
X607500Y188300
X609345Y190100
X616100Y197400
X602800Y203225
X601200Y207700
X603964Y210400
X622873Y204200
X633100Y198300
X629700
X636500
X626300Y198250
X634748Y177708
X631900Y175850
X625500Y159000
X629000
X622000
X633319Y155008
X636719Y154972
X639500Y136490
X621100Y124900
X620000Y112575
X635000Y110500
X638000Y107400
X624726Y107395
X627500Y104900
X630700Y100500
X634000Y97500
X638500Y94000
X642823Y88477
X640677Y91115
X653600Y122400
X648500Y144000
X656200
X656477Y148033
X656642Y151430
X650500Y155000
X643500
X640110Y155272
X648500Y162600
X640461Y181410
X642600Y186400
X646000
X654851Y191978
X657722Y193800
X654100Y221800
X668732Y204555
X666446Y202037
X663800Y199900
X661600Y197300
X673044Y190456
X676200Y181600
X673100Y179455
X661000Y173800
X661600Y156700
X682600Y114300
X699241Y114759
X698970Y118149
X689547Y175500
X689400Y178900
X684700Y179800
X698000Y181500
X687456Y183944
X686700Y187400
X694600Y229800
X715500Y205837
X717000Y187500
X701245Y183800
X704700
X712700Y155978
X718825Y155453
X718200Y150400
Y147000
X709500Y143500
X709900Y139900
X714900Y131900
X715700Y124200
X714000Y118500
X707209Y97500
X718900Y94000
X705145Y93500
X738000Y65700
X731340Y82515
X738500Y90000
X730200Y94900
X726800Y95500
X736900Y98500
X724200Y108400
X739500Y114900
X736300Y118000
X729400Y120200
X732000Y122700
X727448Y128893
X728900Y132976
X727800Y136600
X727187Y140000
X729500Y162300
X733400
X736900
X724400Y176025
X733000Y176200
X727800Y176600
X737000Y188315
X725500Y195500
X734000Y205000
X731000Y210200
X739900Y212800
X739800Y216300
X727400Y227400
X744100Y221900
X743800Y215900
X743000Y211000
X743100Y195500
X746000Y182300
X740300Y164700
X747000Y162000
X750500
X752191Y146613
X745104Y137763
X758176Y135024
X745104Y133763
X749104
X741104
X759400Y131000
X745104Y129763
X757900Y124700
X742100Y118200
X751300
X748800Y115800
X754000Y115100
X756000Y106000
X758916Y104250
X749500Y101500
X752500Y49007
X750100Y16100
X778000Y31307
X774500
X762304Y103957
X765500Y112000
X768500Y114000
X769800Y133000
X766600Y139800
X771300Y140200
X779000Y142000
X765400Y281000
X762000
X787600Y183300
X787800Y179900
X793000Y174500
X796515Y148060
X792515
X788515Y144060
X784515
X796515
X792515
X800515Y148060
Y144060
X805500Y128000
T03
X196800Y62600
X199600Y160100
X239300Y196800
X502500Y6200
X538300Y15200
X699000Y162255
X756400Y110500
X799900Y168800
X809700Y164300
X809600Y160500
X800400Y158500
X809500Y156900
X809000Y149200
X811200Y141600
X811000Y138000
X782000Y137000
X811000Y134000
Y130000
X799000Y125500
Y121500
X784000Y31000
X786500Y13500
X790500Y11000
T04
X25000Y77300
X23400Y81550
X14400Y98000
X14000Y104500
X33000Y105000
X37500
X14000Y109500
X15400Y118000
X10900
X15500Y122800
X11000
X10500Y127500
X15000
X13000Y137000
Y141500
X30200Y145000
X13000Y146000
X30200Y149200
X13100Y150600
X30200Y153400
X30300Y157600
X11500Y159000
X7000
X34000Y161500
X7000Y163700
X11500
X14500Y198000
X4600Y223100
X4500Y228900
Y234800
X4400Y245100
Y256700
X37500Y264000
X12600Y266900
X5000Y275000
X4900Y285700
X15300Y285800
X25200Y286000
X63200Y194900
X70900Y193800
X76200Y187200
X50500Y160000
X45500Y118000
X42000Y105000
X63500Y57500
X68000Y52500
X63500
X73500Y48000
X63500
X68500Y47500
X63500Y43500
X99500Y91500
X104000Y92000
X95500Y93500
X99500Y96000
X104000Y96500
X119400Y102300
X104000Y106600
X119400Y106700
X104000Y111000
X119400Y111200
X104000Y115500
X119400Y115900
X94000Y133000
X98500
X114500Y134050
X103175
X109000
X105775Y137349
X98500Y137500
X94000
X113200Y146700
X117500Y146950
X113100Y151000
X114700Y158800
X119000Y159100
X90700Y177050
X82000Y177500
X86500
X116500Y211200
X100700Y262900
X100000Y267400
X97500Y285450
X102000
X110700Y285550
X106500
X92800Y285600
X136500Y272500
X129000Y268000
X129500Y252500
X122250Y241500
Y237300
Y233000
Y228750
X158700Y213800
X133941Y208863
X138100Y208100
X131003Y205766
X128500Y165000
X123900Y115900
Y111200
Y106700
X123800Y102500
X134100Y96600
X189000Y87700
X192500Y161900
X192600Y166700
X166500Y241000
X186500Y276500
X191100Y276600
X190900Y280800
X186500Y281000
X212400Y281200
X217000Y281000
X212500Y277000
X208000
X238500Y259000
X233500Y258958
X228000Y259000
X217200Y258000
X221300Y255400
X207500Y253000
X211900
X217000Y252900
X203100
X229725Y243450
X234525
X225300Y243400
X238900Y243450
X234525Y239250
X238925Y239200
X225300
X229675Y239000
X238925Y235000
X225300Y234800
X234525
X229700Y234700
X201200Y164200
X212600Y161500
X212300Y157300
X226900Y133300
X236400Y95100
X216261Y74846
X258400Y65600
X240130Y77300
X240565Y113365
X249350Y199400
X252350Y202350
X257000Y213500
X252700
X248300
X247500Y235050
X243300
X247500Y239250
X243300
X251700
X243300Y243450
X247500
X251700
X252500Y259000
X248000
X243000
X253000Y267000
X278200Y281350
X282686Y281336
X294800Y94100
X331500Y278751
X335700
X343600Y270500
X334300
X334500Y266300
X321300Y88200
X349300Y83000
X345100
X354200Y76400
X345089Y73089
X359800Y72700
X353500Y71900
X357000Y69500
X339638Y67138
X353100Y56151
X362700Y69600
X371500Y47000
X375700
X380295Y46779
X371400Y42500
X375600
X380300
X380000Y38100
X467200Y4400
X474000Y9000
X443800Y246100
X496711Y248999
X505200Y215000
X481500Y8900
X497100Y8800
X489600
X527000Y225500
X598814Y240095
X623900Y239600
X615100Y238900
X600900Y230200
X615700
X623400Y230100
X630000Y55300
X646000Y46007
X640000
X654500Y46107
X640500Y55000
X655133Y55833
X653000Y93000
X678400Y114500
X650726Y125724
X678500Y141500
X664212Y147993
X668411Y148089
X667061Y175239
X657500Y258400
X659811Y260757
X656000Y261400
X661308Y263698
X657787Y264179
X655523Y266616
X658667Y267622
X655500Y270500
X710200Y201700
X694500Y159000
X690000
X693500Y148000
X701600Y104900
X701400Y98400
X700089Y91411
X714500Y85500
X715000Y80300
X717000Y74500
X739500Y75500
X722000Y74500
X721200Y65100
X732000Y63500
X721950Y51950
X725632Y49600
X759000Y37507
X753500Y28507
Y24007
Y20007
X755500Y16000
X785500Y8000
X770500Y13007
X761000Y16007
X767500Y19507
Y24007
Y28507
X760500Y29000
X767500Y33207
X764200Y44200
X764300Y49200
X769500Y50000
X781500Y51000
X764500Y54000
X761000Y58500
X792000Y83000
X796500
X764500Y84800
X796500Y87700
X792000
X760400Y88700
X768100Y89000
X783000Y93000
X787500
X777000Y93100
X761300Y95700
X799200Y98600
X774300Y102500
X778500
X799200Y102800
X778500Y107000
X774300
X799000Y107100
Y111900
X783000Y113000
X799000Y116100
X783000Y118500
Y123000
X763600Y168000
X794110Y187679
X789910
X798310Y187779
X764000Y188000
X785830Y188700
X764000Y192810
Y197500
Y202310
X785400Y202800
X793500Y204979
X789000
X789200Y209800
Y214200
Y218700
X784500Y222500
X789000Y223500
X793500
X786000Y228000
X793200Y228400
X786000Y232400
X793200Y232600
X769500Y234500
X786200Y236900
X793200Y237200
X786300Y241500
X793200Y242400
X785000Y245800
X793300Y247200
X785000Y250200
X795400Y251700
X769400Y252700
X785000Y254900
X795300Y256500
Y260800
Y265000
X809700Y285900
X821600Y285500
X810100Y275000
X821900Y273100
X812035Y271067
X810100Y267339
X812000Y263500
X809500Y257000
Y251500
X808700Y247100
Y242900
Y238300
Y234100
X809100Y228600
Y224400
X809200Y218400
Y213700
Y209500
X810500Y196500
Y192300
X803500Y116700
Y112500
X803100Y106000
X820500Y6500
T05
X276811Y263386
X296811
X457913Y45276
X477913
T06
X794032Y27032
X804032
Y37032
X794032
Y47032
X804032
Y57032
X794032
Y67032
X804032
T07
X144000Y67875
Y147125
T08
X42717Y270472
X235630Y75590
X492520Y262598
X761417Y22798
T09
X235630Y174016
X498425Y22798
X755512Y262598
T10
X42717Y191732
T11
X11500Y68500
X12000Y279000
X816000Y280000
T12
X200197Y282677
X298622
T13
X45669Y77185
Y172460
T14
X-19686Y15748
Y573228
X846455
Y15748
M30
